(kicad_pcb
	(version 20260206)
	(generator "pcbnew")
	(generator_version "10.0")
	(general
		(thickness 1.6)
		(legacy_teardrops no)
	)
	(paper "A4")
	(title_block
		(title "timecard-production-celestica-r4006 — R4006-B0001-02_R01.brd")
		(comment 1 "Time Appliance Project (Time Card) / footprints 1090-1094 of 1113")
	)
	(layers
		(0 "F.Cu" signal "TOP")
		(4 "In1.Cu" signal "L02_GND1")
		(6 "In2.Cu" signal "L03_SIG1")
		(8 "In3.Cu" signal "L04_GND2")
		(10 "In4.Cu" signal "L05_VCC1")
		(12 "In5.Cu" signal "L06_VCC2")
		(14 "In6.Cu" signal "L07_GND3")
		(16 "In7.Cu" signal "L08_SIG2")
		(18 "In8.Cu" signal "L09_GND4")
		(2 "B.Cu" signal "BOTTOM")
		(9 "F.Adhes" user "F.Adhesive")
		(11 "B.Adhes" user "B.Adhesive")
		(13 "F.Paste" user "Package Geometry/Pastemask Top")
		(15 "B.Paste" user "Package Geometry/Pastemask Bottom")
		(5 "F.SilkS" user "Ref Des/Silkscreen Top")
		(7 "B.SilkS" user "Ref Des/Silkscreen Bottom")
		(1 "F.Mask" user "Board Geometry/Soldermask Top")
		(3 "B.Mask" user "Board Geometry/Soldermask Bottom")
		(17 "Dwgs.User" user "User.Drawings")
		(19 "Cmts.User" user "User.Comments")
		(21 "Eco1.User" user "User.Eco1")
		(23 "Eco2.User" user "User.Eco2")
		(25 "Edge.Cuts" user "Board Geometry/Outline")
		(27 "Margin" user)
		(31 "F.CrtYd" user "Package Geometry/Place Bound Top")
		(29 "B.CrtYd" user "Package Geometry/Place Bound Bottom")
		(35 "F.Fab" user "Ref Des/Assembly Top")
		(33 "B.Fab" user "Ref Des/Assembly Bottom")
	)
	(footprint ""
		(layer "B.Cu")
		(at 104.6226 -44.45)
		(property "Reference" "C113"
			(at -43.307 1.63195 0)
			(unlocked yes)
			(layer "B.SilkS")
			(effects
				(font
					(size 0.635 0.4064)
					(thickness 0.1524)
				)
				(justify mirror)
			)
		)
		(property "Value" "VAL*"
			(at -0.0762 2.067306 0)
			(unlocked yes)
			(layer "B.Fab")
			(hide yes)
			(effects
				(font
					(size 0.7874 0.5842)
					(thickness 0.1524)
				)
				(justify mirror)
			)
		)
		(property "Device Type" "CAPACITOR-G105-0B104-CK,0.1UF,A"
			(at -0.0508 1.127506 0)
			(unlocked yes)
			(layer "B.Fab")
			(hide yes)
			(effects
				(font
					(size 0.7874 0.5842)
					(thickness 0.1524)
				)
				(justify mirror)
			)
		)
		(property "User Part Number" "PARTNUM*"
			(at -0.1016 4.023106 0)
			(unlocked yes)
			(layer "Cmts.User")
			(hide yes)
			(effects
				(font
					(size 0.7874 0.5842)
					(thickness 0.1524)
				)
				(justify mirror)
			)
		)
		(property "Tolerance" "TOL*"
			(at -0.0762 3.032506 0)
			(unlocked yes)
			(layer "Cmts.User")
			(hide yes)
			(effects
				(font
					(size 0.7874 0.5842)
					(thickness 0.1524)
				)
				(justify mirror)
			)
		)
		(duplicate_pad_numbers_are_jumpers no)
		(fp_line
			(start -1.143 -0.5588)
			(end 1.143 -0.5588)
			(stroke
				(width 0.1)
				(type default)
			)
			(layer "B.SilkS")
		)
		(fp_line
			(start -1.143 0.5588)
			(end -1.143 -0.5588)
			(stroke
				(width 0.1)
				(type default)
			)
			(layer "B.SilkS")
		)
		(fp_line
			(start 1.143 -0.5588)
			(end 1.143 0.5588)
			(stroke
				(width 0.1)
				(type default)
			)
			(layer "B.SilkS")
		)
		(fp_line
			(start 1.143 0.5588)
			(end -1.143 0.5588)
			(stroke
				(width 0.1)
				(type default)
			)
			(layer "B.SilkS")
		)
		(fp_poly
			(pts
				(xy 1.143 0.5588) (xy -1.143 0.5588) (xy -1.143 -0.5588) (xy 1.143 -0.5588)
			)
			(stroke
				(width 0)
				(type default)
			)
			(fill no)
			(layer "B.CrtYd")
		)
		(fp_line
			(start -0.508 -0.3048)
			(end 0.508 -0.3048)
			(stroke
				(width 0.1)
				(type default)
			)
			(layer "B.Fab")
		)
		(fp_line
			(start -0.508 0.3048)
			(end -0.508 -0.3048)
			(stroke
				(width 0.1)
				(type default)
			)
			(layer "B.Fab")
		)
		(fp_line
			(start 0.508 -0.3048)
			(end 0.508 0.3048)
			(stroke
				(width 0.1)
				(type default)
			)
			(layer "B.Fab")
		)
		(fp_line
			(start 0.508 0.3048)
			(end -0.508 0.3048)
			(stroke
				(width 0.1)
				(type default)
			)
			(layer "B.Fab")
		)
		(pad "1" smd rect
			(at 0.5334 0 180)
			(size 0.7112 0.6096)
			(layers "B.Cu" "B.Mask" "B.Paste")
			(net "XP1R8V_FPGA_VCCAUX")
		)
		(pad "2" smd rect
			(at -0.5334 0 180)
			(size 0.7112 0.6096)
			(layers "B.Cu" "B.Mask" "B.Paste")
			(net "SG")
		)
		(zone
			(layer "B.Cu")
			(hatch none 0.5)
			(connect_pads
				(clearance 0)
			)
			(min_thickness 0.25)
			(keepout
				(tracks not_allowed)
				(vias allowed)
				(pads allowed)
				(copperpour not_allowed)
				(footprints allowed)
			)
			(placement
				(enabled no)
				(sheetname "")
			)
			(fill
				(thermal_gap 0.5)
				(thermal_bridge_width 0.5)
				(island_removal_mode 0)
			)
			(polygon
				(pts
					(xy 104.6988 -44.1452) (xy 104.6988 -44.7548) (xy 104.5464 -44.7548) (xy 104.5464 -44.1452)
				)
			)
		)
		(zone
			(layer "B.Cu")
			(hatch none 0.5)
			(connect_pads
				(clearance 0)
			)
			(min_thickness 0.25)
			(keepout
				(tracks allowed)
				(vias not_allowed)
				(pads allowed)
				(copperpour not_allowed)
				(footprints allowed)
			)
			(placement
				(enabled no)
				(sheetname "")
			)
			(fill
				(thermal_gap 0.5)
				(thermal_bridge_width 0.5)
				(island_removal_mode 0)
			)
			(polygon
				(pts
					(xy 104.6988 -44.1452) (xy 104.6988 -44.7548) (xy 104.5464 -44.7548) (xy 104.5464 -44.1452)
				)
			)
		)
	)
	(footprint ""
		(layer "B.Cu")
		(at 92.583 -56.642 180)
		(property "Reference" "C158"
			(at 1.397 1.48463 0)
			(unlocked yes)
			(layer "B.SilkS")
			(effects
				(font
					(size 0.7874 0.5842)
					(thickness 0.1524)
				)
				(justify mirror)
			)
		)
		(property "Value" "VAL*"
			(at -0.0762 3.134106 180)
			(unlocked yes)
			(layer "B.Fab")
			(hide yes)
			(effects
				(font
					(size 0.7874 0.5842)
					(thickness 0.1524)
				)
				(justify mirror)
			)
		)
		(property "Device Type" "CAPACITOR-G107-0F226-CM,22UF,2A"
			(at -0.0508 2.194306 180)
			(unlocked yes)
			(layer "B.Fab")
			(hide yes)
			(effects
				(font
					(size 0.7874 0.5842)
					(thickness 0.1524)
				)
				(justify mirror)
			)
		)
		(property "User Part Number" "PARTNUM*"
			(at -0.1016 5.013706 180)
			(unlocked yes)
			(layer "Cmts.User")
			(hide yes)
			(effects
				(font
					(size 0.7874 0.5842)
					(thickness 0.1524)
				)
				(justify mirror)
			)
		)
		(property "Tolerance" "TOL*"
			(at -0.0762 4.048506 180)
			(unlocked yes)
			(layer "Cmts.User")
			(hide yes)
			(effects
				(font
					(size 0.7874 0.5842)
					(thickness 0.1524)
				)
				(justify mirror)
			)
		)
		(duplicate_pad_numbers_are_jumpers no)
		(fp_line
			(start 1.5748 0.9398)
			(end -1.5748 0.9398)
			(stroke
				(width 0.1)
				(type default)
			)
			(layer "B.SilkS")
		)
		(fp_line
			(start 1.5748 -0.9398)
			(end 1.5748 0.9398)
			(stroke
				(width 0.1)
				(type default)
			)
			(layer "B.SilkS")
		)
		(fp_line
			(start -1.5748 0.9398)
			(end -1.5748 -0.9398)
			(stroke
				(width 0.1)
				(type default)
			)
			(layer "B.SilkS")
		)
		(fp_line
			(start -1.5748 -0.9398)
			(end 1.5748 -0.9398)
			(stroke
				(width 0.1)
				(type default)
			)
			(layer "B.SilkS")
		)
		(fp_rect
			(start -1.5748 -0.9398)
			(end 1.5748 0.9398)
			(stroke
				(width 0)
				(type default)
			)
			(fill no)
			(layer "B.CrtYd")
		)
		(fp_line
			(start 1.016 0.635)
			(end -1.016 0.635)
			(stroke
				(width 0.1)
				(type default)
			)
			(layer "B.Fab")
		)
		(fp_line
			(start 1.016 -0.635)
			(end 1.016 0.635)
			(stroke
				(width 0.1)
				(type default)
			)
			(layer "B.Fab")
		)
		(fp_line
			(start -1.016 0.635)
			(end -1.016 -0.635)
			(stroke
				(width 0.1)
				(type default)
			)
			(layer "B.Fab")
		)
		(fp_line
			(start -1.016 -0.635)
			(end 1.016 -0.635)
			(stroke
				(width 0.1)
				(type default)
			)
			(layer "B.Fab")
		)
		(pad "1" smd rect
			(at 0.8382 0)
			(size 0.9652 1.3716)
			(layers "B.Cu" "B.Mask" "B.Paste")
			(net "XP1R8V_FPGA")
		)
		(pad "2" smd rect
			(at -0.8382 0)
			(size 0.9652 1.3716)
			(layers "B.Cu" "B.Mask" "B.Paste")
			(net "SG")
		)
		(zone
			(layer "B.Cu")
			(hatch none 0.5)
			(connect_pads
				(clearance 0)
			)
			(min_thickness 0.25)
			(keepout
				(tracks allowed)
				(vias not_allowed)
				(pads allowed)
				(copperpour not_allowed)
				(footprints allowed)
			)
			(placement
				(enabled no)
				(sheetname "")
			)
			(fill
				(thermal_gap 0.5)
				(thermal_bridge_width 0.5)
				(island_removal_mode 0)
			)
			(polygon
				(pts
					(xy 92.8116 -56.007) (xy 92.8116 -57.277) (xy 92.3544 -57.277) (xy 92.3544 -56.007)
				)
			)
		)
	)
	(footprint ""
		(layer "B.Cu")
		(at 158.877 -50.513996 -90)
		(property "Reference" "R102"
			(at 7.874 -1.35763 270)
			(unlocked yes)
			(layer "B.SilkS")
			(effects
				(font
					(size 0.7874 0.5842)
					(thickness 0.1524)
				)
				(justify mirror)
			)
		)
		(property "Value" "VAL*"
			(at -0.02032 2.13233 270)
			(unlocked yes)
			(layer "B.Fab")
			(hide yes)
			(effects
				(font
					(size 0.7874 0.5842)
					(thickness 0.1524)
				)
				(justify mirror)
			)
		)
		(property "Device Type" "RESISTOR-G155-11001-01,1KOHM,1%"
			(at -0.008382 1.210564 270)
			(unlocked yes)
			(layer "B.Fab")
			(hide yes)
			(effects
				(font
					(size 0.7874 0.5842)
					(thickness 0.1524)
				)
				(justify mirror)
			)
		)
		(property "User Part Number" "PARTNUM*"
			(at -0.02032 4.024884 270)
			(unlocked yes)
			(layer "Cmts.User")
			(hide yes)
			(effects
				(font
					(size 0.7874 0.5842)
					(thickness 0.1524)
				)
				(justify mirror)
			)
		)
		(property "Tolerance" "TOL*"
			(at -0.044704 3.05435 270)
			(unlocked yes)
			(layer "Cmts.User")
			(hide yes)
			(effects
				(font
					(size 0.7874 0.5842)
					(thickness 0.1524)
				)
				(justify mirror)
			)
		)
		(duplicate_pad_numbers_are_jumpers no)
		(fp_line
			(start -1.143 0.5588)
			(end -1.143 -0.5588)
			(stroke
				(width 0.1)
				(type default)
			)
			(layer "B.SilkS")
		)
		(fp_line
			(start 1.143 0.5588)
			(end -1.143 0.5588)
			(stroke
				(width 0.1)
				(type default)
			)
			(layer "B.SilkS")
		)
		(fp_line
			(start -1.143 -0.5588)
			(end 1.143 -0.5588)
			(stroke
				(width 0.1)
				(type default)
			)
			(layer "B.SilkS")
		)
		(fp_line
			(start 1.143 -0.5588)
			(end 1.143 0.5588)
			(stroke
				(width 0.1)
				(type default)
			)
			(layer "B.SilkS")
		)
		(fp_rect
			(start -1.143 -0.5588)
			(end 1.143 0.5588)
			(stroke
				(width 0)
				(type default)
			)
			(fill no)
			(layer "B.CrtYd")
		)
		(fp_line
			(start -0.508 0.3048)
			(end -0.508 -0.3048)
			(stroke
				(width 0.1)
				(type default)
			)
			(layer "B.Fab")
		)
		(fp_line
			(start 0.508 0.3048)
			(end -0.508 0.3048)
			(stroke
				(width 0.1)
				(type default)
			)
			(layer "B.Fab")
		)
		(fp_line
			(start -0.508 -0.3048)
			(end 0.508 -0.3048)
			(stroke
				(width 0.1)
				(type default)
			)
			(layer "B.Fab")
		)
		(fp_line
			(start 0.508 -0.3048)
			(end 0.508 0.3048)
			(stroke
				(width 0.1)
				(type default)
			)
			(layer "B.Fab")
		)
		(pad "1" smd rect
			(at 0.5334 0 90)
			(size 0.7112 0.6096)
			(layers "B.Cu" "B.Mask" "B.Paste")
			(net "XP5R0V_USB_CONN_DET")
		)
		(pad "2" smd rect
			(at -0.5334 0 90)
			(size 0.7112 0.6096)
			(layers "B.Cu" "B.Mask" "B.Paste")
			(net "UNNAMED_527_RESISTOR_I201_2")
		)
		(zone
			(layer "B.Cu")
			(hatch none 0.5)
			(connect_pads
				(clearance 0)
			)
			(min_thickness 0.25)
			(keepout
				(tracks allowed)
				(vias not_allowed)
				(pads allowed)
				(copperpour not_allowed)
				(footprints allowed)
			)
			(placement
				(enabled no)
				(sheetname "")
			)
			(fill
				(thermal_gap 0.5)
				(thermal_bridge_width 0.5)
				(island_removal_mode 0)
			)
			(polygon
				(pts
					(xy 159.1818 -50.590196) (xy 158.5722 -50.590196) (xy 158.5722 -50.437796) (xy 159.1818 -50.437796)
				)
			)
		)
	)
	(footprint ""
		(layer "B.Cu")
		(at 140.335 -65.913)
		(property "Reference" "R28"
			(at 1.73863 0.381 270)
			(unlocked yes)
			(layer "B.SilkS")
			(effects
				(font
					(size 0.7874 0.5842)
					(thickness 0.1524)
				)
				(justify mirror)
			)
		)
		(property "Value" "VAL*"
			(at -0.02032 2.13233 0)
			(unlocked yes)
			(layer "B.Fab")
			(hide yes)
			(effects
				(font
					(size 0.7874 0.5842)
					(thickness 0.1524)
				)
				(justify mirror)
			)
		)
		(property "Tolerance" "TOL*"
			(at -0.044704 3.05435 0)
			(unlocked yes)
			(layer "Cmts.User")
			(hide yes)
			(effects
				(font
					(size 0.7874 0.5842)
					(thickness 0.1524)
				)
				(justify mirror)
			)
		)
		(property "User Part Number" "PARTNUM*"
			(at -0.02032 4.024884 0)
			(unlocked yes)
			(layer "Cmts.User")
			(hide yes)
			(effects
				(font
					(size 0.7874 0.5842)
					(thickness 0.1524)
				)
				(justify mirror)
			)
		)
		(property "Device Type" "RESISTOR-G155-100R0-J0,0OHM,-"
			(at -0.008382 1.210564 0)
			(unlocked yes)
			(layer "B.Fab")
			(hide yes)
			(effects
				(font
					(size 0.7874 0.5842)
					(thickness 0.1524)
				)
				(justify mirror)
			)
		)
		(duplicate_pad_numbers_are_jumpers no)
		(fp_line
			(start -1.143 -0.5588)
			(end 1.143 -0.5588)
			(stroke
				(width 0.1)
				(type default)
			)
			(layer "B.SilkS")
		)
		(fp_line
			(start -1.143 0.5588)
			(end -1.143 -0.5588)
			(stroke
				(width 0.1)
				(type default)
			)
			(layer "B.SilkS")
		)
		(fp_line
			(start 1.143 -0.5588)
			(end 1.143 0.5588)
			(stroke
				(width 0.1)
				(type default)
			)
			(layer "B.SilkS")
		)
		(fp_line
			(start 1.143 0.5588)
			(end -1.143 0.5588)
			(stroke
				(width 0.1)
				(type default)
			)
			(layer "B.SilkS")
		)
		(fp_rect
			(start 1.143 0.5588)
			(end -1.143 -0.5588)
			(stroke
				(width 0)
				(type default)
			)
			(fill no)
			(layer "B.CrtYd")
		)
		(fp_line
			(start -0.508 -0.3048)
			(end 0.508 -0.3048)
			(stroke
				(width 0.1)
				(type default)
			)
			(layer "B.Fab")
		)
		(fp_line
			(start -0.508 0.3048)
			(end -0.508 -0.3048)
			(stroke
				(width 0.1)
				(type default)
			)
			(layer "B.Fab")
		)
		(fp_line
			(start 0.508 -0.3048)
			(end 0.508 0.3048)
			(stroke
				(width 0.1)
				(type default)
			)
			(layer "B.Fab")
		)
		(fp_line
			(start 0.508 0.3048)
			(end -0.508 0.3048)
			(stroke
				(width 0.1)
				(type default)
			)
			(layer "B.Fab")
		)
		(pad "1" smd rect
			(at 0.5334 0 180)
			(size 0.7112 0.6096)
			(layers "B.Cu" "B.Mask" "B.Paste")
			(net "PCIE_CONN_TCK")
		)
		(pad "2" smd rect
			(at -0.5334 0 180)
			(size 0.7112 0.6096)
			(layers "B.Cu" "B.Mask" "B.Paste")
			(net "FPGA_TCK")
		)
		(zone
			(layer "B.Cu")
			(hatch none 0.5)
			(connect_pads
				(clearance 0)
			)
			(min_thickness 0.25)
			(keepout
				(tracks allowed)
				(vias not_allowed)
				(pads allowed)
				(copperpour not_allowed)
				(footprints allowed)
			)
			(placement
				(enabled no)
				(sheetname "")
			)
			(fill
				(thermal_gap 0.5)
				(thermal_bridge_width 0.5)
				(island_removal_mode 0)
			)
			(polygon
				(pts
					(xy 140.4112 -65.6082) (xy 140.4112 -66.2178) (xy 140.2588 -66.2178) (xy 140.2588 -65.6082)
				)
			)
		)
	)
	(footprint ""
		(layer "B.Cu")
		(at 109.3724 -46.1264 90)
		(property "Reference" "C115"
			(at -1.6764 -42.98315 270)
			(unlocked yes)
			(layer "B.SilkS")
			(effects
				(font
					(size 0.635 0.4064)
					(thickness 0.1524)
				)
				(justify mirror)
			)
		)
		(property "Value" "VAL*"
			(at -0.0762 2.067306 90)
			(unlocked yes)
			(layer "B.Fab")
			(hide yes)
			(effects
				(font
					(size 0.7874 0.5842)
					(thickness 0.1524)
				)
				(justify mirror)
			)
		)
		(property "Device Type" "CAPACITOR-G105-0B104-CK,0.1UF,A"
			(at -0.0508 1.127506 90)
			(unlocked yes)
			(layer "B.Fab")
			(hide yes)
			(effects
				(font
					(size 0.7874 0.5842)
					(thickness 0.1524)
				)
				(justify mirror)
			)
		)
		(property "User Part Number" "PARTNUM*"
			(at -0.1016 4.023106 90)
			(unlocked yes)
			(layer "Cmts.User")
			(hide yes)
			(effects
				(font
					(size 0.7874 0.5842)
					(thickness 0.1524)
				)
				(justify mirror)
			)
		)
		(property "Tolerance" "TOL*"
			(at -0.0762 3.032506 90)
			(unlocked yes)
			(layer "Cmts.User")
			(hide yes)
			(effects
				(font
					(size 0.7874 0.5842)
					(thickness 0.1524)
				)
				(justify mirror)
			)
		)
		(duplicate_pad_numbers_are_jumpers no)
		(fp_line
			(start 1.143 -0.5588)
			(end 1.143 0.5588)
			(stroke
				(width 0.1)
				(type default)
			)
			(layer "B.SilkS")
		)
		(fp_line
			(start -1.143 -0.5588)
			(end 1.143 -0.5588)
			(stroke
				(width 0.1)
				(type default)
			)
			(layer "B.SilkS")
		)
		(fp_line
			(start 1.143 0.5588)
			(end -1.143 0.5588)
			(stroke
				(width 0.1)
				(type default)
			)
			(layer "B.SilkS")
		)
		(fp_line
			(start -1.143 0.5588)
			(end -1.143 -0.5588)
			(stroke
				(width 0.1)
				(type default)
			)
			(layer "B.SilkS")
		)
		(fp_poly
			(pts
				(xy 1.143 0.5588) (xy -1.143 0.5588) (xy -1.143 -0.5588) (xy 1.143 -0.5588)
			)
			(stroke
				(width 0)
				(type default)
			)
			(fill no)
			(layer "B.CrtYd")
		)
		(fp_line
			(start 0.508 -0.3048)
			(end 0.508 0.3048)
			(stroke
				(width 0.1)
				(type default)
			)
			(layer "B.Fab")
		)
		(fp_line
			(start -0.508 -0.3048)
			(end 0.508 -0.3048)
			(stroke
				(width 0.1)
				(type default)
			)
			(layer "B.Fab")
		)
		(fp_line
			(start 0.508 0.3048)
			(end -0.508 0.3048)
			(stroke
				(width 0.1)
				(type default)
			)
			(layer "B.Fab")
		)
		(fp_line
			(start -0.508 0.3048)
			(end -0.508 -0.3048)
			(stroke
				(width 0.1)
				(type default)
			)
			(layer "B.Fab")
		)
		(pad "1" smd rect
			(at 0.5334 0 270)
			(size 0.7112 0.6096)
			(layers "B.Cu" "B.Mask" "B.Paste")
			(net "XP3R3V_FPGA")
		)
		(pad "2" smd rect
			(at -0.5334 0 270)
			(size 0.7112 0.6096)
			(layers "B.Cu" "B.Mask" "B.Paste")
			(net "SG")
		)
		(zone
			(layer "B.Cu")
			(hatch none 0.5)
			(connect_pads
				(clearance 0)
			)
			(min_thickness 0.25)
			(keepout
				(tracks not_allowed)
				(vias allowed)
				(pads allowed)
				(copperpour not_allowed)
				(footprints allowed)
			)
			(placement
				(enabled no)
				(sheetname "")
			)
			(fill
				(thermal_gap 0.5)
				(thermal_bridge_width 0.5)
				(island_removal_mode 0)
			)
			(polygon
				(pts
					(xy 109.6772 -46.2026) (xy 109.0676 -46.2026) (xy 109.0676 -46.0502) (xy 109.6772 -46.0502)
				)
			)
		)
		(zone
			(layer "B.Cu")
			(hatch none 0.5)
			(connect_pads
				(clearance 0)
			)
			(min_thickness 0.25)
			(keepout
				(tracks allowed)
				(vias not_allowed)
				(pads allowed)
				(copperpour not_allowed)
				(footprints allowed)
			)
			(placement
				(enabled no)
				(sheetname "")
			)
			(fill
				(thermal_gap 0.5)
				(thermal_bridge_width 0.5)
				(island_removal_mode 0)
			)
			(polygon
				(pts
					(xy 109.6772 -46.2026) (xy 109.0676 -46.2026) (xy 109.0676 -46.0502) (xy 109.6772 -46.0502)
				)
			)
		)
	)
)
